# T6G (Grand Teton) — schematic netlist excerpt (pin names and nets, part order shuffled) for the footprints in the layout excerpt that follows; sources: Cadence DE-HDL packaged netlist, KiCad conversion of 04192023_DAF0TMB3IC0_F0TG_MB_C_brd_V02_OCP.brd

J106  CONN112_10137002101LF  CONN112_10137002-101LF IO  pkg HSD_F112D8_P2W1-2_RDH  page 116
  A1  = PRSNT_CABLE_SWB_B1_N
  A2  = GND
  A3  = FM_SWB_PWRGD
  A4  = GND
  A5  = NC_J106_A5
  A6  = GND
  A7  = PRSNT_CABLE_GPU_A1_N
  A8  = GND
  B1  = GND
  B2  = P5E_CPU0_P2_RX_BUF_DN<1>
  B3  = GND
  B4  = P5E_CPU0_P2_RX_BUF_DN<3>
  B5  = GND
  B6  = P5E_CPU0_P2_RX_BUF_DN<5>
  B7  = GND
  B8  = P5E_CPU0_P2_RX_BUF_DN<7>
  C1  = P5E_CPU0_P2_RX_BUF_DN<0>
  C2  = P5E_CPU0_P2_RX_BUF_DP<1>
  C3  = P5E_CPU0_P2_RX_BUF_DN<2>
  C4  = P5E_CPU0_P2_RX_BUF_DP<3>
  C5  = P5E_CPU0_P2_RX_BUF_DN<4>
  C6  = P5E_CPU0_P2_RX_BUF_DP<5>
  C7  = P5E_CPU0_P2_RX_BUF_DN<6>
  C8  = P5E_CPU0_P2_RX_BUF_DP<7>
  D1  = P5E_CPU0_P2_RX_BUF_DP<0>
  D2  = GND
  D3  = P5E_CPU0_P2_RX_BUF_DP<2>
  D4  = GND
  D5  = P5E_CPU0_P2_RX_BUF_DP<4>
  D6  = GND
  D7  = P5E_CPU0_P2_RX_BUF_DP<6>
  D8  = GND
  E1  = GND
  E2  = P5E_CPU0_P3_RX_BUF_DN<1>
  E3  = GND
  E4  = P5E_CPU0_P3_RX_BUF_DN<3>
  E5  = GND
  E6  = P5E_CPU0_P3_RX_BUF_DN<5>
  E7  = GND
  E8  = P5E_CPU0_P3_RX_BUF_DN<7>
  F1  = P5E_CPU0_P3_RX_BUF_DN<0>
  F2  = P5E_CPU0_P3_RX_BUF_DP<1>
  F3  = P5E_CPU0_P3_RX_BUF_DN<2>
  F4  = P5E_CPU0_P3_RX_BUF_DP<3>
  F5  = P5E_CPU0_P3_RX_BUF_DN<4>
  F6  = P5E_CPU0_P3_RX_BUF_DP<5>
  F7  = P5E_CPU0_P3_RX_BUF_DN<6>
  F8  = P5E_CPU0_P3_RX_BUF_DP<7>
  G1  = P5E_CPU0_P3_RX_BUF_DP<0>
  G2  = GND
  G3  = P5E_CPU0_P3_RX_BUF_DP<2>
  G4  = GND
  G5  = P5E_CPU0_P3_RX_BUF_DP<4>
  G6  = GND
  G7  = P5E_CPU0_P3_RX_BUF_DP<6>
  G8  = GND
  H1  = GND
  H2  = P5E_CPU0_P2_TX_BUF_C_DN<1>
  H3  = GND
  H4  = P5E_CPU0_P2_TX_BUF_C_DN<3>
  H5  = GND
  H6  = P5E_CPU0_P2_TX_BUF_C_DN<5>
  H7  = GND
  H8  = P5E_CPU0_P2_TX_BUF_C_DN<7>
  I1  = P5E_CPU0_P2_TX_BUF_C_DN<0>
  I2  = P5E_CPU0_P2_TX_BUF_C_DP<1>
  I3  = P5E_CPU0_P2_TX_BUF_C_DN<2>
  I4  = P5E_CPU0_P2_TX_BUF_C_DP<3>
  I5  = P5E_CPU0_P2_TX_BUF_C_DN<4>
  I6  = P5E_CPU0_P2_TX_BUF_C_DP<5>
  I7  = P5E_CPU0_P2_TX_BUF_C_DN<6>
  I8  = P5E_CPU0_P2_TX_BUF_C_DP<7>
  J1  = P5E_CPU0_P2_TX_BUF_C_DP<0>
  J2  = GND
  J3  = P5E_CPU0_P2_TX_BUF_C_DP<2>
  J4  = GND
  J5  = P5E_CPU0_P2_TX_BUF_C_DP<4>
  J6  = GND
  J7  = P5E_CPU0_P2_TX_BUF_C_DP<6>
  J8  = GND
  K1  = GND
  K2  = P5E_CPU0_P3_TX_BUF_C_DN<1>
  K3  = GND
  K4  = P5E_CPU0_P3_TX_BUF_C_DN<3>
  K5  = GND
  K6  = P5E_CPU0_P3_TX_BUF_C_DN<5>
  K7  = GND
  K8  = P5E_CPU0_P3_TX_BUF_C_DN<7>
  L1  = P5E_CPU0_P3_TX_BUF_C_DN<0>
  L2  = P5E_CPU0_P3_TX_BUF_C_DP<1>
  L3  = P5E_CPU0_P3_TX_BUF_C_DN<2>
  L4  = P5E_CPU0_P3_TX_BUF_C_DP<3>
  L5  = P5E_CPU0_P3_TX_BUF_C_DN<4>
  L6  = P5E_CPU0_P3_TX_BUF_C_DP<5>
  L7  = P5E_CPU0_P3_TX_BUF_C_DN<6>
  L8  = P5E_CPU0_P3_TX_BUF_C_DP<7>
  M1  = P5E_CPU0_P3_TX_BUF_C_DP<0>
  M2  = GND
  M3  = P5E_CPU0_P3_TX_BUF_C_DP<2>
  M4  = GND
  M5  = P5E_CPU0_P3_TX_BUF_C_DP<4>
  M6  = GND
  M7  = P5E_CPU0_P3_TX_BUF_C_DP<6>
  M8  = GND
  N1  = GND
  N2  = I3C_BMC_SWB_BUF_SDA
  N3  = GND
  N4  = I3C_BMC_SWB_BUF_SCL
  N5  = GND
  N6  = UART_BMC_BIC_RX
  N7  = GND
  N8  = UART_BMC_BIC_TX

(kicad_pcb
	(version 20260206)
	(generator "pcbnew")
	(generator_version "10.0")
	(general
		(thickness 1.6)
		(legacy_teardrops no)
	)
	(paper "A4")
	(title_block
		(title "04192023_DAF0TMB3IC0_F0TG_MB_C_brd_V02_OCP.brd")
		(comment 1 "Grand Teton / footprint 703 of 8354 (J106), pads 1-31 of 48")
	)
	(layers
		(0 "F.Cu" signal "TOP")
		(4 "In1.Cu" signal "GND")
		(6 "In2.Cu" signal "IN1")
		(8 "In3.Cu" signal "GND1")
		(10 "In4.Cu" signal "IN2")
		(12 "In5.Cu" signal "GND2")
		(14 "In6.Cu" signal "IN3")
		(16 "In7.Cu" signal "GND3")
		(18 "In8.Cu" signal "VCC")
		(20 "In9.Cu" signal "VCC1")
		(22 "In10.Cu" signal "GND4")
		(24 "In11.Cu" signal "IN4")
		(26 "In12.Cu" signal "GND5")
		(28 "In13.Cu" signal "IN5")
		(30 "In14.Cu" signal "GND6")
		(32 "In15.Cu" signal "IN6")
		(34 "In16.Cu" signal "GND7")
		(2 "B.Cu" signal "BOTTOM")
		(9 "F.Adhes" user "F.Adhesive")
		(11 "B.Adhes" user "B.Adhesive")
		(13 "F.Paste" user "Package Geometry/Pastemask Top")
		(15 "B.Paste" user "Package Geometry/Pastemask Bottom")
		(5 "F.SilkS" user "Ref Des/Silkscreen Top")
		(7 "B.SilkS" user "Ref Des/Silkscreen Bottom")
		(1 "F.Mask" user "Board Geometry/Soldermask Top")
		(3 "B.Mask" user "Board Geometry/Soldermask Bottom")
		(17 "Dwgs.User" user "User.Drawings")
		(19 "Cmts.User" user "User.Comments")
		(21 "Eco1.User" user "User.Eco1")
		(23 "Eco2.User" user "User.Eco2")
		(25 "Edge.Cuts" user "Board Geometry/Outline")
		(27 "Margin" user)
		(31 "F.CrtYd" user "Package Geometry/Place Bound Top")
		(29 "B.CrtYd" user "Package Geometry/Place Bound Bottom")
		(35 "F.Fab" user "Ref Des/Assembly Top")
		(33 "B.Fab" user "Ref Des/Assembly Bottom")
	)
	(footprint ""
		(layer "F.Cu")
		(at 381.749808 -440.489848)
		(property "Reference" "J106"
			(at -7.604506 17.991328 0)
			(unlocked yes)
			(layer "F.SilkS")
			(effects
				(font
					(size 0.7874 0.5842)
					(thickness 0.1524)
				)
				(justify left)
			)
		)
		(property "Value" ""
			(at 0 0 0)
			(layer "F.Fab")
			(effects
				(font
					(size 1.27 1.27)
				)
			)
		)
		(duplicate_pad_numbers_are_jumpers no)
		(pad "A1" thru_hole rect
			(at 0 0 180)
			(size 0.766318 0.766318)
			(drill 0.359918)
			(layers "*.Cu" "*.Mask")
			(remove_unused_layers no)
			(net "PRSNT_CABLE_SWB_B1_N")
			(clearance 0.0508)
			(thermal_gap 0.0508)
			(padstack
				(mode front_inner_back)
				(layer "Inner"
					(shape circle)
					(size 0.766318 0.766318)
					(clearance 0.0508)
				)
				(layer "B.Cu"
					(shape rect)
					(size 0.766318 0.766318)
					(clearance 0.0508)
				)
			)
		)
		(pad "A2" thru_hole circle
			(at 1.999996 0.199898 180)
			(size 0.906272 0.906272)
			(drill 0.499872)
			(layers "*.Cu" "*.Mask")
			(remove_unused_layers no)
			(net "GND")
			(clearance 0.0508)
			(thermal_gap 0.0508)
		)
		(pad "A3" thru_hole circle
			(at 3.999992 0 180)
			(size 0.766318 0.766318)
			(drill 0.359918)
			(layers "*.Cu" "*.Mask")
			(remove_unused_layers no)
			(net "FM_SWB_PWRGD")
			(clearance 0.0508)
			(thermal_gap 0.0508)
		)
		(pad "A4" thru_hole circle
			(at 5.999988 0.199898 180)
			(size 0.906272 0.906272)
			(drill 0.499872)
			(layers "*.Cu" "*.Mask")
			(remove_unused_layers no)
			(net "GND")
			(clearance 0.0508)
			(thermal_gap 0.0508)
		)
		(pad "A5" thru_hole circle
			(at 7.999984 0 180)
			(size 0.766318 0.766318)
			(drill 0.359918)
			(layers "*.Cu" "*.Mask")
			(remove_unused_layers no)
			(net "NC_J106_A5")
			(clearance 0.0508)
			(thermal_gap 0.0508)
		)
		(pad "A6" thru_hole circle
			(at 9.99998 0.199898 180)
			(size 0.906272 0.906272)
			(drill 0.499872)
			(layers "*.Cu" "*.Mask")
			(remove_unused_layers no)
			(net "GND")
			(clearance 0.0508)
			(thermal_gap 0.0508)
		)
		(pad "A7" thru_hole circle
			(at 11.999976 0 180)
			(size 0.766318 0.766318)
			(drill 0.359918)
			(layers "*.Cu" "*.Mask")
			(remove_unused_layers no)
			(net "PRSNT_CABLE_GPU_A1_N")
			(clearance 0.0508)
			(thermal_gap 0.0508)
		)
		(pad "A8" thru_hole circle
			(at 13.999972 0.199898 180)
			(size 0.906272 0.906272)
			(drill 0.499872)
			(layers "*.Cu" "*.Mask")
			(remove_unused_layers no)
			(net "GND")
			(clearance 0.0508)
			(thermal_gap 0.0508)
		)
		(pad "B1" thru_hole circle
			(at 0 1.199896 180)
			(size 0.906272 0.906272)
			(drill 0.499872)
			(layers "*.Cu" "*.Mask")
			(remove_unused_layers no)
			(net "GND")
			(clearance 0.0508)
			(thermal_gap 0.0508)
		)
		(pad "B3" thru_hole circle
			(at 3.999992 1.199896 180)
			(size 0.906272 0.906272)
			(drill 0.499872)
			(layers "*.Cu" "*.Mask")
			(remove_unused_layers no)
			(net "GND")
			(clearance 0.0508)
			(thermal_gap 0.0508)
		)
		(pad "B5" thru_hole circle
			(at 7.999984 1.199896 180)
			(size 0.906272 0.906272)
			(drill 0.499872)
			(layers "*.Cu" "*.Mask")
			(remove_unused_layers no)
			(net "GND")
			(clearance 0.0508)
			(thermal_gap 0.0508)
		)
		(pad "B7" thru_hole circle
			(at 11.999976 1.199896 180)
			(size 0.906272 0.906272)
			(drill 0.499872)
			(layers "*.Cu" "*.Mask")
			(remove_unused_layers no)
			(net "GND")
			(clearance 0.0508)
			(thermal_gap 0.0508)
		)
		(pad "D2" thru_hole circle
			(at 1.999996 3.800094 180)
			(size 0.906272 0.906272)
			(drill 0.499872)
			(layers "*.Cu" "*.Mask")
			(remove_unused_layers no)
			(net "GND")
			(clearance 0.0508)
			(thermal_gap 0.0508)
		)
		(pad "D4" thru_hole circle
			(at 5.999988 3.800094 180)
			(size 0.906272 0.906272)
			(drill 0.499872)
			(layers "*.Cu" "*.Mask")
			(remove_unused_layers no)
			(net "GND")
			(clearance 0.0508)
			(thermal_gap 0.0508)
		)
		(pad "D6" thru_hole circle
			(at 9.99998 3.800094 180)
			(size 0.906272 0.906272)
			(drill 0.499872)
			(layers "*.Cu" "*.Mask")
			(remove_unused_layers no)
			(net "GND")
			(clearance 0.0508)
			(thermal_gap 0.0508)
		)
		(pad "D8" thru_hole circle
			(at 13.999972 3.800094 180)
			(size 0.906272 0.906272)
			(drill 0.499872)
			(layers "*.Cu" "*.Mask")
			(remove_unused_layers no)
			(net "GND")
			(clearance 0.0508)
			(thermal_gap 0.0508)
		)
		(pad "E1" thru_hole circle
			(at 0 4.800092 180)
			(size 0.906272 0.906272)
			(drill 0.499872)
			(layers "*.Cu" "*.Mask")
			(remove_unused_layers no)
			(net "GND")
			(clearance 0.0508)
			(thermal_gap 0.0508)
		)
		(pad "E3" thru_hole circle
			(at 3.999992 4.800092 180)
			(size 0.906272 0.906272)
			(drill 0.499872)
			(layers "*.Cu" "*.Mask")
			(remove_unused_layers no)
			(net "GND")
			(clearance 0.0508)
			(thermal_gap 0.0508)
		)
		(pad "E5" thru_hole circle
			(at 7.999984 4.800092 180)
			(size 0.906272 0.906272)
			(drill 0.499872)
			(layers "*.Cu" "*.Mask")
			(remove_unused_layers no)
			(net "GND")
			(clearance 0.0508)
			(thermal_gap 0.0508)
		)
		(pad "E7" thru_hole circle
			(at 11.999976 4.800092 180)
			(size 0.906272 0.906272)
			(drill 0.499872)
			(layers "*.Cu" "*.Mask")
			(remove_unused_layers no)
			(net "GND")
			(clearance 0.0508)
			(thermal_gap 0.0508)
		)
		(pad "G2" thru_hole circle
			(at 1.999996 7.400036 180)
			(size 0.906272 0.906272)
			(drill 0.499872)
			(layers "*.Cu" "*.Mask")
			(remove_unused_layers no)
			(net "GND")
			(clearance 0.0508)
			(thermal_gap 0.0508)
		)
		(pad "G4" thru_hole circle
			(at 5.999988 7.400036 180)
			(size 0.906272 0.906272)
			(drill 0.499872)
			(layers "*.Cu" "*.Mask")
			(remove_unused_layers no)
			(net "GND")
			(clearance 0.0508)
			(thermal_gap 0.0508)
		)
		(pad "G6" thru_hole circle
			(at 9.99998 7.400036 180)
			(size 0.906272 0.906272)
			(drill 0.499872)
			(layers "*.Cu" "*.Mask")
			(remove_unused_layers no)
			(net "GND")
			(clearance 0.0508)
			(thermal_gap 0.0508)
		)
		(pad "G8" thru_hole circle
			(at 13.999972 7.400036 180)
			(size 0.906272 0.906272)
			(drill 0.499872)
			(layers "*.Cu" "*.Mask")
			(remove_unused_layers no)
			(net "GND")
			(clearance 0.0508)
			(thermal_gap 0.0508)
		)
		(pad "H1" thru_hole circle
			(at 0 8.400034 180)
			(size 0.906272 0.906272)
			(drill 0.499872)
			(layers "*.Cu" "*.Mask")
			(remove_unused_layers no)
			(net "GND")
			(clearance 0.0508)
			(thermal_gap 0.0508)
		)
		(pad "H3" thru_hole circle
			(at 3.999992 8.400034 180)
			(size 0.906272 0.906272)
			(drill 0.499872)
			(layers "*.Cu" "*.Mask")
			(remove_unused_layers no)
			(net "GND")
			(clearance 0.0508)
			(thermal_gap 0.0508)
		)
		(pad "H5" thru_hole circle
			(at 7.999984 8.400034 180)
			(size 0.906272 0.906272)
			(drill 0.499872)
			(layers "*.Cu" "*.Mask")
			(remove_unused_layers no)
			(net "GND")
			(clearance 0.0508)
			(thermal_gap 0.0508)
		)
		(pad "H7" thru_hole circle
			(at 11.999976 8.400034 180)
			(size 0.906272 0.906272)
			(drill 0.499872)
			(layers "*.Cu" "*.Mask")
			(remove_unused_layers no)
			(net "GND")
			(clearance 0.0508)
			(thermal_gap 0.0508)
		)
		(pad "J2" thru_hole circle
			(at 1.999996 10.999978 180)
			(size 0.906272 0.906272)
			(drill 0.499872)
			(layers "*.Cu" "*.Mask")
			(remove_unused_layers no)
			(net "GND")
			(clearance 0.0508)
			(thermal_gap 0.0508)
		)
		(pad "J4" thru_hole circle
			(at 5.999988 10.999978 180)
			(size 0.906272 0.906272)
			(drill 0.499872)
			(layers "*.Cu" "*.Mask")
			(remove_unused_layers no)
			(net "GND")
			(clearance 0.0508)
			(thermal_gap 0.0508)
		)
		(pad "J6" thru_hole circle
			(at 9.99998 10.999978 180)
			(size 0.906272 0.906272)
			(drill 0.499872)
			(layers "*.Cu" "*.Mask")
			(remove_unused_layers no)
			(net "GND")
			(clearance 0.0508)
			(thermal_gap 0.0508)
		)
	)
)
